# GMSL Deserializer — assets/stackup.csv
Name;Type;Material;Thickness[mm];Constant;User-Name
F.Mask;Top Solder Mask;;0.01;;F_Mask
F.Cu;copper;;0.035;;F_Cu
dielectric 1;core;FR4;0.474;4.5;dielectric 1
In1.Cu;copper;;0.035;;In1_Cu
dielectric 2;prepreg;FR4;0.474;4.5;dielectric 2
In2.Cu;copper;;0.035;;In2_Cu
dielectric 3;core;FR4;0.474;4.5;dielectric 3
B.Cu;copper;;0.035;;B_Cu
B.Mask;Bottom Solder Mask;;0.01;;B_Mask
